# TIMECARD (Time Appliance Project (Time Card)) — schematic netlist excerpt (pin names and nets, part order shuffled) for the footprints in the layout excerpt that follows; sources: Cadence DE-HDL packaged netlist, KiCad conversion of R4006-B0001-02_R01.brd

R374  RESISTOR  100OHM 1%  pkg SMC_0402R_H016  page 26 : \1\ = FPGA_OUT_SMA3_LED_BLUE_N ; \2\ = UNNAMED_14_LED4PV14_I267_1

(kicad_pcb
	(version 20260206)
	(generator "pcbnew")
	(generator_version "10.0")
	(general
		(thickness 1.6)
		(legacy_teardrops no)
	)
	(paper "A4")
	(title_block
		(title "timecard-production-celestica-r4006 — R4006-B0001-02_R01.brd")
		(comment 1 "Time Appliance Project (Time Card) / footprints 40-40 of 1113")
	)
	(layers
		(0 "F.Cu" signal "TOP")
		(4 "In1.Cu" signal "L02_GND1")
		(6 "In2.Cu" signal "L03_SIG1")
		(8 "In3.Cu" signal "L04_GND2")
		(10 "In4.Cu" signal "L05_VCC1")
		(12 "In5.Cu" signal "L06_VCC2")
		(14 "In6.Cu" signal "L07_GND3")
		(16 "In7.Cu" signal "L08_SIG2")
		(18 "In8.Cu" signal "L09_GND4")
		(2 "B.Cu" signal "BOTTOM")
		(9 "F.Adhes" user "F.Adhesive")
		(11 "B.Adhes" user "B.Adhesive")
		(13 "F.Paste" user "Package Geometry/Pastemask Top")
		(15 "B.Paste" user "Package Geometry/Pastemask Bottom")
		(5 "F.SilkS" user "Ref Des/Silkscreen Top")
		(7 "B.SilkS" user "Ref Des/Silkscreen Bottom")
		(1 "F.Mask" user "Board Geometry/Soldermask Top")
		(3 "B.Mask" user "Board Geometry/Soldermask Bottom")
		(17 "Dwgs.User" user "User.Drawings")
		(19 "Cmts.User" user "User.Comments")
		(21 "Eco1.User" user "User.Eco1")
		(23 "Eco2.User" user "User.Eco2")
		(25 "Edge.Cuts" user "Board Geometry/Outline")
		(27 "Margin" user)
		(31 "F.CrtYd" user "Package Geometry/Place Bound Top")
		(29 "B.CrtYd" user "Package Geometry/Place Bound Bottom")
		(35 "F.Fab" user "Ref Des/Assembly Top")
		(33 "B.Fab" user "Ref Des/Assembly Bottom")
	)
	(footprint ""
		(layer "F.Cu")
		(at 6.1468 -68.201032 90)
		(property "Reference" "R374"
			(at 3.553968 -0.26543 90)
			(unlocked yes)
			(layer "F.SilkS")
			(effects
				(font
					(size 0.7874 0.5842)
					(thickness 0.1524)
				)
			)
		)
		(property "Value" "VAL*"
			(at 0.02032 2.13233 90)
			(unlocked yes)
			(layer "F.Fab")
			(hide yes)
			(effects
				(font
					(size 0.7874 0.5842)
					(thickness 0.1524)
				)
			)
		)
		(property "Device Type" "RESISTOR-G155-11000-01,100OHM,A"
			(at 0.008382 1.210564 90)
			(unlocked yes)
			(layer "F.Fab")
			(hide yes)
			(effects
				(font
					(size 0.7874 0.5842)
					(thickness 0.1524)
				)
			)
		)
		(property "User Part Number" "PARTNUM*"
			(at 0.02032 4.024884 90)
			(unlocked yes)
			(layer "Cmts.User")
			(hide yes)
			(effects
				(font
					(size 0.7874 0.5842)
					(thickness 0.1524)
				)
			)
		)
		(property "Tolerance" "TOL*"
			(at 0.044704 3.05435 90)
			(unlocked yes)
			(layer "Cmts.User")
			(hide yes)
			(effects
				(font
					(size 0.7874 0.5842)
					(thickness 0.1524)
				)
			)
		)
		(duplicate_pad_numbers_are_jumpers no)
		(fp_line
			(start 1.143 -0.5588)
			(end -1.143 -0.5588)
			(stroke
				(width 0.1)
				(type default)
			)
			(layer "F.SilkS")
		)
		(fp_line
			(start -1.143 -0.5588)
			(end -1.143 0.5588)
			(stroke
				(width 0.1)
				(type default)
			)
			(layer "F.SilkS")
		)
		(fp_line
			(start 1.143 0.5588)
			(end 1.143 -0.5588)
			(stroke
				(width 0.1)
				(type default)
			)
			(layer "F.SilkS")
		)
		(fp_line
			(start -1.143 0.5588)
			(end 1.143 0.5588)
			(stroke
				(width 0.1)
				(type default)
			)
			(layer "F.SilkS")
		)
		(fp_poly
			(pts
				(xy -1.143 0.5588) (xy 1.143 0.5588) (xy 1.143 -0.5588) (xy -1.143 -0.5588)
			)
			(stroke
				(width 0)
				(type default)
			)
			(fill no)
			(layer "F.CrtYd")
		)
		(fp_line
			(start 0.508 -0.3048)
			(end -0.508 -0.3048)
			(stroke
				(width 0.1)
				(type default)
			)
			(layer "F.Fab")
		)
		(fp_line
			(start -0.508 -0.3048)
			(end -0.508 0.3048)
			(stroke
				(width 0.1)
				(type default)
			)
			(layer "F.Fab")
		)
		(fp_line
			(start 0.508 0.3048)
			(end 0.508 -0.3048)
			(stroke
				(width 0.1)
				(type default)
			)
			(layer "F.Fab")
		)
		(fp_line
			(start -0.508 0.3048)
			(end 0.508 0.3048)
			(stroke
				(width 0.1)
				(type default)
			)
			(layer "F.Fab")
		)
		(pad "1" smd rect
			(at -0.5334 0 90)
			(size 0.7112 0.6096)
			(layers "F.Cu" "F.Mask" "F.Paste")
			(net "FPGA_OUT_SMA3_LED_BLUE_N")
		)
		(pad "2" smd rect
			(at 0.5334 0 90)
			(size 0.7112 0.6096)
			(layers "F.Cu" "F.Mask" "F.Paste")
			(net "UNNAMED_14_LED4PV14_I267_1")
		)
		(zone
			(layer "F.Cu")
			(hatch none 0.5)
			(connect_pads
				(clearance 0)
			)
			(min_thickness 0.25)
			(keepout
				(tracks allowed)
				(vias not_allowed)
				(pads allowed)
				(copperpour not_allowed)
				(footprints allowed)
			)
			(placement
				(enabled no)
				(sheetname "")
			)
			(fill
				(thermal_gap 0.5)
				(thermal_bridge_width 0.5)
				(island_removal_mode 0)
			)
			(polygon
				(pts
					(xy 6.4516 -68.124832) (xy 6.4516 -68.277232) (xy 5.842 -68.277232) (xy 5.842 -68.124832)
				)
			)
		)
		(zone
			(layer "F.Cu")
			(hatch none 0.5)
			(connect_pads
				(clearance 0)
			)
			(min_thickness 0.25)
			(keepout
				(tracks not_allowed)
				(vias allowed)
				(pads allowed)
				(copperpour not_allowed)
				(footprints allowed)
			)
			(placement
				(enabled no)
				(sheetname "")
			)
			(fill
				(thermal_gap 0.5)
				(thermal_bridge_width 0.5)
				(island_removal_mode 0)
			)
			(polygon
				(pts
					(xy 6.4516 -68.124832) (xy 6.4516 -68.277232) (xy 5.842 -68.277232) (xy 5.842 -68.124832)
				)
			)
		)
	)
)
